(kicad_pcb
	(version 20260206)
	(generator "pcbnew")
	(generator_version "10.0")
	(general
		(thickness 1.6)
		(legacy_teardrops no)
	)
	(paper "A4")
	(title_block
		(title "01162023_DA0F0TEBIF0_F0T_Expander_BD_F_brd_V02_OCP.brd")
		(comment 1 "Grand Teton / footprints 7475-7482 of 9728")
	)
	(layers
		(0 "F.Cu" signal "TOP")
		(4 "In1.Cu" signal "GND")
		(6 "In2.Cu" signal "VCC")
		(8 "In3.Cu" signal "VCC1")
		(10 "In4.Cu" signal "GND1")
		(12 "In5.Cu" signal "IN1")
		(14 "In6.Cu" signal "GND2")
		(16 "In7.Cu" signal "IN2")
		(18 "In8.Cu" signal "GND3")
		(20 "In9.Cu" signal "IN3")
		(22 "In10.Cu" signal "GND4")
		(24 "In11.Cu" signal "IN4")
		(26 "In12.Cu" signal "GND5")
		(28 "In13.Cu" signal "IN5")
		(30 "In14.Cu" signal "GND6")
		(32 "In15.Cu" signal "IN6")
		(34 "In16.Cu" signal "GND7")
		(2 "B.Cu" signal "BOTTOM")
		(9 "F.Adhes" user "F.Adhesive")
		(11 "B.Adhes" user "B.Adhesive")
		(13 "F.Paste" user "Package Geometry/Pastemask Top")
		(15 "B.Paste" user "Package Geometry/Pastemask Bottom")
		(5 "F.SilkS" user "Ref Des/Silkscreen Top")
		(7 "B.SilkS" user "Ref Des/Silkscreen Bottom")
		(1 "F.Mask" user "Board Geometry/Soldermask Top")
		(3 "B.Mask" user "Board Geometry/Soldermask Bottom")
		(17 "Dwgs.User" user "User.Drawings")
		(19 "Cmts.User" user "User.Comments")
		(21 "Eco1.User" user "User.Eco1")
		(23 "Eco2.User" user "User.Eco2")
		(25 "Edge.Cuts" user "Board Geometry/Outline")
		(27 "Margin" user)
		(31 "F.CrtYd" user "Package Geometry/Place Bound Top")
		(29 "B.CrtYd" user "Package Geometry/Place Bound Bottom")
		(35 "F.Fab" user "Ref Des/Assembly Top")
		(33 "B.Fab" user "Ref Des/Assembly Bottom")
	)
	(footprint ""
		(layer "B.Cu")
		(at 295.575228 -109.481366 180)
		(property "Reference" "R287"
			(at 0 0 0)
			(layer "B.SilkS")
			(hide yes)
			(effects
				(font
					(size 1.27 1.27)
				)
				(justify mirror)
			)
		)
		(property "Value" ""
			(at 0 0 0)
			(layer "B.Fab")
			(effects
				(font
					(size 1.27 1.27)
				)
				(justify mirror)
			)
		)
		(duplicate_pad_numbers_are_jumpers no)
		(fp_line
			(start 0.7874 0.4064)
			(end 0.7874 -0.4064)
			(stroke
				(width 0.1524)
				(type default)
			)
			(layer "B.SilkS")
		)
		(fp_line
			(start 0.7874 -0.4064)
			(end -0.7874 -0.4064)
			(stroke
				(width 0.1524)
				(type default)
			)
			(layer "B.SilkS")
		)
		(fp_line
			(start -0.7874 0.4064)
			(end 0.7874 0.4064)
			(stroke
				(width 0.1524)
				(type default)
			)
			(layer "B.SilkS")
		)
		(fp_line
			(start -0.7874 -0.4064)
			(end -0.7874 0.4064)
			(stroke
				(width 0.1524)
				(type default)
			)
			(layer "B.SilkS")
		)
		(fp_line
			(start 0.67945 0.3048)
			(end 0.67945 -0.305054)
			(stroke
				(width 0.1)
				(type default)
			)
			(layer "B.Fab")
		)
		(fp_line
			(start 0.67945 -0.305054)
			(end 0.12065 -0.305054)
			(stroke
				(width 0.1)
				(type default)
			)
			(layer "B.Fab")
		)
		(fp_line
			(start 0.12065 0.3048)
			(end 0.67945 0.3048)
			(stroke
				(width 0.1)
				(type default)
			)
			(layer "B.Fab")
		)
		(fp_line
			(start 0.12065 0.2794)
			(end 0.12065 0.3048)
			(stroke
				(width 0.1)
				(type default)
			)
			(layer "B.Fab")
		)
		(fp_line
			(start 0.12065 -0.2794)
			(end -0.12065 -0.2794)
			(stroke
				(width 0.1)
				(type default)
			)
			(layer "B.Fab")
		)
		(fp_line
			(start 0.12065 -0.305054)
			(end 0.12065 -0.2794)
			(stroke
				(width 0.1)
				(type default)
			)
			(layer "B.Fab")
		)
		(fp_line
			(start -0.120396 0.3048)
			(end -0.120396 0.2794)
			(stroke
				(width 0.1)
				(type default)
			)
			(layer "B.Fab")
		)
		(fp_line
			(start -0.120396 0.2794)
			(end 0.12065 0.2794)
			(stroke
				(width 0.1)
				(type default)
			)
			(layer "B.Fab")
		)
		(fp_line
			(start -0.12065 -0.2794)
			(end -0.12065 -0.3048)
			(stroke
				(width 0.1)
				(type default)
			)
			(layer "B.Fab")
		)
		(fp_line
			(start -0.12065 -0.3048)
			(end -0.67945 -0.3048)
			(stroke
				(width 0.1)
				(type default)
			)
			(layer "B.Fab")
		)
		(fp_line
			(start -0.67945 0.3048)
			(end -0.120396 0.3048)
			(stroke
				(width 0.1)
				(type default)
			)
			(layer "B.Fab")
		)
		(fp_line
			(start -0.67945 -0.3048)
			(end -0.67945 0.3048)
			(stroke
				(width 0.1)
				(type default)
			)
			(layer "B.Fab")
		)
		(pad "1" smd circle
			(at 0.40005 0)
			(size 0 0)
			(layers "B.Cu" "B.Mask" "B.Paste")
			(net "NIC5_BIF1_N")
		)
		(pad "2" smd circle
			(at -0.40005 0)
			(size 0 0)
			(layers "B.Cu" "B.Mask" "B.Paste")
			(net "GND")
		)
	)
	(footprint ""
		(layer "B.Cu")
		(at 374.015 -234.569 180)
		(property "Reference" "C2584"
			(at 0 0 0)
			(layer "B.SilkS")
			(hide yes)
			(effects
				(font
					(size 1.27 1.27)
				)
				(justify mirror)
			)
		)
		(property "Value" ""
			(at 0 0 0)
			(layer "B.Fab")
			(effects
				(font
					(size 1.27 1.27)
				)
				(justify mirror)
			)
		)
		(duplicate_pad_numbers_are_jumpers no)
		(fp_line
			(start 0.7874 0.4064)
			(end 0.7874 -0.4064)
			(stroke
				(width 0.1524)
				(type default)
			)
			(layer "B.SilkS")
		)
		(fp_line
			(start 0.7874 -0.4064)
			(end -0.7874 -0.4064)
			(stroke
				(width 0.1524)
				(type default)
			)
			(layer "B.SilkS")
		)
		(fp_line
			(start -0.7874 0.4064)
			(end 0.7874 0.4064)
			(stroke
				(width 0.1524)
				(type default)
			)
			(layer "B.SilkS")
		)
		(fp_line
			(start -0.7874 -0.4064)
			(end -0.7874 0.4064)
			(stroke
				(width 0.1524)
				(type default)
			)
			(layer "B.SilkS")
		)
		(fp_line
			(start 0.67945 0.3048)
			(end 0.67945 -0.305054)
			(stroke
				(width 0.1)
				(type default)
			)
			(layer "B.Fab")
		)
		(fp_line
			(start 0.67945 -0.305054)
			(end 0.12065 -0.305054)
			(stroke
				(width 0.1)
				(type default)
			)
			(layer "B.Fab")
		)
		(fp_line
			(start 0.12065 0.3048)
			(end 0.67945 0.3048)
			(stroke
				(width 0.1)
				(type default)
			)
			(layer "B.Fab")
		)
		(fp_line
			(start 0.12065 0.2794)
			(end 0.12065 0.3048)
			(stroke
				(width 0.1)
				(type default)
			)
			(layer "B.Fab")
		)
		(fp_line
			(start 0.12065 -0.2794)
			(end -0.12065 -0.2794)
			(stroke
				(width 0.1)
				(type default)
			)
			(layer "B.Fab")
		)
		(fp_line
			(start 0.12065 -0.305054)
			(end 0.12065 -0.2794)
			(stroke
				(width 0.1)
				(type default)
			)
			(layer "B.Fab")
		)
		(fp_line
			(start -0.120396 0.3048)
			(end -0.120396 0.2794)
			(stroke
				(width 0.1)
				(type default)
			)
			(layer "B.Fab")
		)
		(fp_line
			(start -0.120396 0.2794)
			(end 0.12065 0.2794)
			(stroke
				(width 0.1)
				(type default)
			)
			(layer "B.Fab")
		)
		(fp_line
			(start -0.12065 -0.2794)
			(end -0.12065 -0.3048)
			(stroke
				(width 0.1)
				(type default)
			)
			(layer "B.Fab")
		)
		(fp_line
			(start -0.12065 -0.3048)
			(end -0.67945 -0.3048)
			(stroke
				(width 0.1)
				(type default)
			)
			(layer "B.Fab")
		)
		(fp_line
			(start -0.67945 0.3048)
			(end -0.120396 0.3048)
			(stroke
				(width 0.1)
				(type default)
			)
			(layer "B.Fab")
		)
		(fp_line
			(start -0.67945 -0.3048)
			(end -0.67945 0.3048)
			(stroke
				(width 0.1)
				(type default)
			)
			(layer "B.Fab")
		)
		(pad "1" smd circle
			(at 0.40005 0)
			(size 0 0)
			(layers "B.Cu" "B.Mask" "B.Paste")
			(net "P3V3_AUX")
		)
		(pad "2" smd circle
			(at -0.40005 0)
			(size 0 0)
			(layers "B.Cu" "B.Mask" "B.Paste")
			(net "GND")
		)
	)
	(footprint ""
		(layer "B.Cu")
		(at 46.736 -291.624766)
		(property "Reference" "C3060"
			(at 0 0 0)
			(layer "B.SilkS")
			(hide yes)
			(effects
				(font
					(size 1.27 1.27)
				)
				(justify mirror)
			)
		)
		(property "Value" ""
			(at 0 0 0)
			(layer "B.Fab")
			(effects
				(font
					(size 1.27 1.27)
				)
				(justify mirror)
			)
		)
		(duplicate_pad_numbers_are_jumpers no)
		(fp_line
			(start -0.299974 -0.150114)
			(end -0.299974 0.150114)
			(stroke
				(width 0.1)
				(type default)
			)
			(layer "B.Fab")
		)
		(fp_line
			(start -0.299974 0.150114)
			(end 0.299974 0.150114)
			(stroke
				(width 0.1)
				(type default)
			)
			(layer "B.Fab")
		)
		(fp_line
			(start 0.299974 -0.150114)
			(end -0.299974 -0.150114)
			(stroke
				(width 0.1)
				(type default)
			)
			(layer "B.Fab")
		)
		(fp_line
			(start 0.299974 0.150114)
			(end 0.299974 -0.150114)
			(stroke
				(width 0.1)
				(type default)
			)
			(layer "B.Fab")
		)
		(pad "1" smd rect
			(at 0.2667 0 180)
			(size 0.3048 0.381)
			(layers "B.Cu" "B.Mask" "B.Paste")
			(net "PCEPLL7_VDDA18_PEX0")
		)
		(pad "2" smd rect
			(at -0.2667 0 180)
			(size 0.3048 0.381)
			(layers "B.Cu" "B.Mask" "B.Paste")
			(net "GND")
		)
	)
	(footprint ""
		(layer "B.Cu")
		(at 236.18952 -288.197544)
		(property "Reference" "PC254"
			(at 0 0 0)
			(layer "B.SilkS")
			(hide yes)
			(effects
				(font
					(size 1.27 1.27)
				)
				(justify mirror)
			)
		)
		(property "Value" ""
			(at 0 0 0)
			(layer "B.Fab")
			(effects
				(font
					(size 1.27 1.27)
				)
				(justify mirror)
			)
		)
		(duplicate_pad_numbers_are_jumpers no)
		(fp_line
			(start -1.524 -0.762)
			(end -1.524 0.762)
			(stroke
				(width 0.1524)
				(type default)
			)
			(layer "B.SilkS")
		)
		(fp_line
			(start -1.524 0.762)
			(end 1.524 0.762)
			(stroke
				(width 0.1524)
				(type default)
			)
			(layer "B.SilkS")
		)
		(fp_line
			(start 1.524 -0.762)
			(end -1.524 -0.762)
			(stroke
				(width 0.1524)
				(type default)
			)
			(layer "B.SilkS")
		)
		(fp_line
			(start 1.524 0.762)
			(end 1.524 -0.762)
			(stroke
				(width 0.1524)
				(type default)
			)
			(layer "B.SilkS")
		)
		(fp_line
			(start -1.1049 -0.724916)
			(end 1.1049 -0.724916)
			(stroke
				(width 0.1)
				(type default)
			)
			(layer "B.Fab")
		)
		(fp_line
			(start -1.1049 0.724916)
			(end -1.1049 -0.724916)
			(stroke
				(width 0.1)
				(type default)
			)
			(layer "B.Fab")
		)
		(fp_line
			(start 1.1049 -0.724916)
			(end 1.1049 0.724916)
			(stroke
				(width 0.1)
				(type default)
			)
			(layer "B.Fab")
		)
		(fp_line
			(start 1.1049 0.724916)
			(end -1.1049 0.724916)
			(stroke
				(width 0.1)
				(type default)
			)
			(layer "B.Fab")
		)
		(pad "1" smd rect
			(at 0.889 0)
			(size 1.016 1.27)
			(layers "B.Cu" "B.Mask" "B.Paste")
			(net "P1V25_PEX2_R")
		)
		(pad "2" smd rect
			(at -0.889 0)
			(size 1.016 1.27)
			(layers "B.Cu" "B.Mask" "B.Paste")
			(net "GND")
		)
	)
	(footprint ""
		(layer "B.Cu")
		(at 294.69969 -290.199826 90)
		(property "Reference" "C1711"
			(at 0 0 90)
			(layer "B.SilkS")
			(hide yes)
			(effects
				(font
					(size 1.27 1.27)
				)
				(justify mirror)
			)
		)
		(property "Value" ""
			(at 0 0 90)
			(layer "B.Fab")
			(effects
				(font
					(size 1.27 1.27)
				)
				(justify mirror)
			)
		)
		(duplicate_pad_numbers_are_jumpers no)
		(fp_line
			(start 0.299974 -0.150114)
			(end -0.299974 -0.150114)
			(stroke
				(width 0.1)
				(type default)
			)
			(layer "B.Fab")
		)
		(fp_line
			(start -0.299974 -0.150114)
			(end -0.299974 0.150114)
			(stroke
				(width 0.1)
				(type default)
			)
			(layer "B.Fab")
		)
		(fp_line
			(start 0.299974 0.150114)
			(end 0.299974 -0.150114)
			(stroke
				(width 0.1)
				(type default)
			)
			(layer "B.Fab")
		)
		(fp_line
			(start -0.299974 0.150114)
			(end 0.299974 0.150114)
			(stroke
				(width 0.1)
				(type default)
			)
			(layer "B.Fab")
		)
		(pad "1" smd rect
			(at 0.2667 0 270)
			(size 0.3048 0.381)
			(layers "B.Cu" "B.Mask" "B.Paste")
			(net "P0V8_SERDES_VDDA_PEX2")
		)
		(pad "2" smd rect
			(at -0.2667 0 270)
			(size 0.3048 0.381)
			(layers "B.Cu" "B.Mask" "B.Paste")
			(net "GND")
		)
	)
	(footprint ""
		(layer "B.Cu")
		(at 302.061626 -251.787406 90)
		(property "Reference" "R4099"
			(at 0 0 90)
			(layer "B.SilkS")
			(hide yes)
			(effects
				(font
					(size 1.27 1.27)
				)
				(justify mirror)
			)
		)
		(property "Value" ""
			(at 0 0 90)
			(layer "B.Fab")
			(effects
				(font
					(size 1.27 1.27)
				)
				(justify mirror)
			)
		)
		(duplicate_pad_numbers_are_jumpers no)
		(fp_line
			(start 0.7874 -0.4064)
			(end -0.7874 -0.4064)
			(stroke
				(width 0.1524)
				(type default)
			)
			(layer "B.SilkS")
		)
		(fp_line
			(start -0.7874 -0.4064)
			(end -0.7874 0.4064)
			(stroke
				(width 0.1524)
				(type default)
			)
			(layer "B.SilkS")
		)
		(fp_line
			(start 0.7874 0.4064)
			(end 0.7874 -0.4064)
			(stroke
				(width 0.1524)
				(type default)
			)
			(layer "B.SilkS")
		)
		(fp_line
			(start -0.7874 0.4064)
			(end 0.7874 0.4064)
			(stroke
				(width 0.1524)
				(type default)
			)
			(layer "B.SilkS")
		)
		(fp_line
			(start 0.67945 -0.305054)
			(end 0.12065 -0.305054)
			(stroke
				(width 0.1)
				(type default)
			)
			(layer "B.Fab")
		)
		(fp_line
			(start 0.12065 -0.305054)
			(end 0.12065 -0.2794)
			(stroke
				(width 0.1)
				(type default)
			)
			(layer "B.Fab")
		)
		(fp_line
			(start -0.12065 -0.3048)
			(end -0.67945 -0.3048)
			(stroke
				(width 0.1)
				(type default)
			)
			(layer "B.Fab")
		)
		(fp_line
			(start -0.67945 -0.3048)
			(end -0.67945 0.3048)
			(stroke
				(width 0.1)
				(type default)
			)
			(layer "B.Fab")
		)
		(fp_line
			(start 0.12065 -0.2794)
			(end -0.12065 -0.2794)
			(stroke
				(width 0.1)
				(type default)
			)
			(layer "B.Fab")
		)
		(fp_line
			(start -0.12065 -0.2794)
			(end -0.12065 -0.3048)
			(stroke
				(width 0.1)
				(type default)
			)
			(layer "B.Fab")
		)
		(fp_line
			(start 0.12065 0.2794)
			(end 0.12065 0.3048)
			(stroke
				(width 0.1)
				(type default)
			)
			(layer "B.Fab")
		)
		(fp_line
			(start -0.120396 0.2794)
			(end 0.12065 0.2794)
			(stroke
				(width 0.1)
				(type default)
			)
			(layer "B.Fab")
		)
		(fp_line
			(start 0.67945 0.3048)
			(end 0.67945 -0.305054)
			(stroke
				(width 0.1)
				(type default)
			)
			(layer "B.Fab")
		)
		(fp_line
			(start 0.12065 0.3048)
			(end 0.67945 0.3048)
			(stroke
				(width 0.1)
				(type default)
			)
			(layer "B.Fab")
		)
		(fp_line
			(start -0.120396 0.3048)
			(end -0.120396 0.2794)
			(stroke
				(width 0.1)
				(type default)
			)
			(layer "B.Fab")
		)
		(fp_line
			(start -0.67945 0.3048)
			(end -0.120396 0.3048)
			(stroke
				(width 0.1)
				(type default)
			)
			(layer "B.Fab")
		)
		(pad "1" smd circle
			(at 0.40005 0 270)
			(size 0 0)
			(layers "B.Cu" "B.Mask" "B.Paste")
			(net "SMB_MB_BMC_R_SDA")
		)
		(pad "2" smd circle
			(at -0.40005 0 270)
			(size 0 0)
			(layers "B.Cu" "B.Mask" "B.Paste")
			(net "P3V3_AUX")
		)
	)
	(footprint ""
		(layer "B.Cu")
		(at 130.539744 -203.193142 180)
		(property "Reference" "R921"
			(at 0 0 0)
			(layer "B.SilkS")
			(hide yes)
			(effects
				(font
					(size 1.27 1.27)
				)
				(justify mirror)
			)
		)
		(property "Value" ""
			(at 0 0 0)
			(layer "B.Fab")
			(effects
				(font
					(size 1.27 1.27)
				)
				(justify mirror)
			)
		)
		(duplicate_pad_numbers_are_jumpers no)
		(fp_line
			(start 0.7874 0.4064)
			(end 0.7874 -0.4064)
			(stroke
				(width 0.1524)
				(type default)
			)
			(layer "B.SilkS")
		)
		(fp_line
			(start 0.7874 -0.4064)
			(end -0.7874 -0.4064)
			(stroke
				(width 0.1524)
				(type default)
			)
			(layer "B.SilkS")
		)
		(fp_line
			(start -0.7874 0.4064)
			(end 0.7874 0.4064)
			(stroke
				(width 0.1524)
				(type default)
			)
			(layer "B.SilkS")
		)
		(fp_line
			(start -0.7874 -0.4064)
			(end -0.7874 0.4064)
			(stroke
				(width 0.1524)
				(type default)
			)
			(layer "B.SilkS")
		)
		(fp_line
			(start 0.67945 0.3048)
			(end 0.67945 -0.305054)
			(stroke
				(width 0.1)
				(type default)
			)
			(layer "B.Fab")
		)
		(fp_line
			(start 0.67945 -0.305054)
			(end 0.12065 -0.305054)
			(stroke
				(width 0.1)
				(type default)
			)
			(layer "B.Fab")
		)
		(fp_line
			(start 0.12065 0.3048)
			(end 0.67945 0.3048)
			(stroke
				(width 0.1)
				(type default)
			)
			(layer "B.Fab")
		)
		(fp_line
			(start 0.12065 0.2794)
			(end 0.12065 0.3048)
			(stroke
				(width 0.1)
				(type default)
			)
			(layer "B.Fab")
		)
		(fp_line
			(start 0.12065 -0.2794)
			(end -0.12065 -0.2794)
			(stroke
				(width 0.1)
				(type default)
			)
			(layer "B.Fab")
		)
		(fp_line
			(start 0.12065 -0.305054)
			(end 0.12065 -0.2794)
			(stroke
				(width 0.1)
				(type default)
			)
			(layer "B.Fab")
		)
		(fp_line
			(start -0.120396 0.3048)
			(end -0.120396 0.2794)
			(stroke
				(width 0.1)
				(type default)
			)
			(layer "B.Fab")
		)
		(fp_line
			(start -0.120396 0.2794)
			(end 0.12065 0.2794)
			(stroke
				(width 0.1)
				(type default)
			)
			(layer "B.Fab")
		)
		(fp_line
			(start -0.12065 -0.2794)
			(end -0.12065 -0.3048)
			(stroke
				(width 0.1)
				(type default)
			)
			(layer "B.Fab")
		)
		(fp_line
			(start -0.12065 -0.3048)
			(end -0.67945 -0.3048)
			(stroke
				(width 0.1)
				(type default)
			)
			(layer "B.Fab")
		)
		(fp_line
			(start -0.67945 0.3048)
			(end -0.120396 0.3048)
			(stroke
				(width 0.1)
				(type default)
			)
			(layer "B.Fab")
		)
		(fp_line
			(start -0.67945 -0.3048)
			(end -0.67945 0.3048)
			(stroke
				(width 0.1)
				(type default)
			)
			(layer "B.Fab")
		)
		(pad "1" smd circle
			(at 0.40005 0)
			(size 0 0)
			(layers "B.Cu" "B.Mask" "B.Paste")
			(net "FT4232_CLI_EEPROM_R_CS")
		)
		(pad "2" smd circle
			(at -0.40005 0)
			(size 0 0)
			(layers "B.Cu" "B.Mask" "B.Paste")
			(net "FT4232_CLI_EEPROM_CS")
		)
	)
	(footprint ""
		(layer "B.Cu")
		(at 16.954246 -208.970372)
		(property "Reference" "C4417"
			(at 0 0 0)
			(layer "B.SilkS")
			(hide yes)
			(effects
				(font
					(size 1.27 1.27)
				)
				(justify mirror)
			)
		)
		(property "Value" ""
			(at 0 0 0)
			(layer "B.Fab")
			(effects
				(font
					(size 1.27 1.27)
				)
				(justify mirror)
			)
		)
		(duplicate_pad_numbers_are_jumpers no)
		(fp_line
			(start -0.7874 -0.4064)
			(end -0.7874 0.4064)
			(stroke
				(width 0.1524)
				(type default)
			)
			(layer "B.SilkS")
		)
		(fp_line
			(start -0.7874 0.4064)
			(end 0.7874 0.4064)
			(stroke
				(width 0.1524)
				(type default)
			)
			(layer "B.SilkS")
		)
		(fp_line
			(start 0.7874 -0.4064)
			(end -0.7874 -0.4064)
			(stroke
				(width 0.1524)
				(type default)
			)
			(layer "B.SilkS")
		)
		(fp_line
			(start 0.7874 0.4064)
			(end 0.7874 -0.4064)
			(stroke
				(width 0.1524)
				(type default)
			)
			(layer "B.SilkS")
		)
		(fp_line
			(start -0.67945 -0.3048)
			(end -0.67945 0.3048)
			(stroke
				(width 0.1)
				(type default)
			)
			(layer "B.Fab")
		)
		(fp_line
			(start -0.67945 0.3048)
			(end -0.120396 0.3048)
			(stroke
				(width 0.1)
				(type default)
			)
			(layer "B.Fab")
		)
		(fp_line
			(start -0.12065 -0.3048)
			(end -0.67945 -0.3048)
			(stroke
				(width 0.1)
				(type default)
			)
			(layer "B.Fab")
		)
		(fp_line
			(start -0.12065 -0.2794)
			(end -0.12065 -0.3048)
			(stroke
				(width 0.1)
				(type default)
			)
			(layer "B.Fab")
		)
		(fp_line
			(start -0.120396 0.2794)
			(end 0.12065 0.2794)
			(stroke
				(width 0.1)
				(type default)
			)
			(layer "B.Fab")
		)
		(fp_line
			(start -0.120396 0.3048)
			(end -0.120396 0.2794)
			(stroke
				(width 0.1)
				(type default)
			)
			(layer "B.Fab")
		)
		(fp_line
			(start 0.12065 -0.305054)
			(end 0.12065 -0.2794)
			(stroke
				(width 0.1)
				(type default)
			)
			(layer "B.Fab")
		)
		(fp_line
			(start 0.12065 -0.2794)
			(end -0.12065 -0.2794)
			(stroke
				(width 0.1)
				(type default)
			)
			(layer "B.Fab")
		)
		(fp_line
			(start 0.12065 0.2794)
			(end 0.12065 0.3048)
			(stroke
				(width 0.1)
				(type default)
			)
			(layer "B.Fab")
		)
		(fp_line
			(start 0.12065 0.3048)
			(end 0.67945 0.3048)
			(stroke
				(width 0.1)
				(type default)
			)
			(layer "B.Fab")
		)
		(fp_line
			(start 0.67945 -0.305054)
			(end 0.12065 -0.305054)
			(stroke
				(width 0.1)
				(type default)
			)
			(layer "B.Fab")
		)
		(fp_line
			(start 0.67945 0.3048)
			(end 0.67945 -0.305054)
			(stroke
				(width 0.1)
				(type default)
			)
			(layer "B.Fab")
		)
		(pad "1" smd circle
			(at 0.40005 0 180)
			(size 0 0)
			(layers "B.Cu" "B.Mask" "B.Paste")
			(net "P1V8_PLL0_PEX0")
		)
		(pad "2" smd circle
			(at -0.40005 0 180)
			(size 0 0)
			(layers "B.Cu" "B.Mask" "B.Paste")
			(net "GND")
		)
	)
)
